(kicad_pcb
	(version 20240108)
	(generator "pcbnew")
	(generator_version "8.0")
	(general
		(thickness 1.62)
		(legacy_teardrops no)
	)
	(paper "A4")
	(title_block
		(title "Jetson Orin Baseboard")
		(date "2025-03-12")
		(rev "1.3.4")
		(company "Antmicro Ltd")
		(comment 1 "www.antmicro.com")
		(comment 9 "footprints 552-555 of 677")
	)
	(layers
		(0 "F.Cu" signal)
		(1 "In1.Cu" signal)
		(2 "In2.Cu" signal)
		(3 "In3.Cu" signal)
		(4 "In4.Cu" jumper)
		(5 "In5.Cu" signal)
		(6 "In6.Cu" signal)
		(31 "B.Cu" signal)
		(32 "B.Adhes" user "B.Adhesive")
		(33 "F.Adhes" user "F.Adhesive")
		(34 "B.Paste" user)
		(35 "F.Paste" user)
		(36 "B.SilkS" user "B.Silkscreen")
		(37 "F.SilkS" user "F.Silkscreen")
		(38 "B.Mask" user)
		(39 "F.Mask" user)
		(40 "Dwgs.User" user "User.Drawings")
		(41 "Cmts.User" user "User.Comments")
		(42 "Eco1.User" user "User.Eco1")
		(43 "Eco2.User" user "User.Eco2")
		(44 "Edge.Cuts" user)
		(45 "Margin" user)
		(46 "B.CrtYd" user "B.Courtyard")
		(47 "F.CrtYd" user "F.Courtyard")
		(48 "B.Fab" user)
		(49 "F.Fab" user)
	)
	(footprint "antmicro-footprints:C_0402_1005Metric"
		(layer "B.Cu")
		(at 126.735 87.75)
		(descr "Capacitor SMD 0402")
		(tags "capacitor SMD 0402")
		(property "Reference" "C18"
			(at 2.965 0.4 180)
			(layer "B.SilkS")
			(effects
				(font
					(size 0.7 0.7)
					(thickness 0.15)
				)
				(justify left bottom mirror)
			)
		)
		(property "Value" "C_220n_0402"
			(at 0 -1.4 180)
			(layer "B.Fab")
			(effects
				(font
					(size 0.7 0.7)
					(thickness 0.15)
				)
				(justify left bottom mirror)
			)
		)
		(property "Footprint" "antmicro-footprints:C_0402_1005Metric"
			(at 0 0 0)
			(layer "F.Fab")
			(hide yes)
			(effects
				(font
					(size 1.27 1.27)
					(thickness 0.15)
				)
			)
		)
		(property "Datasheet" "https://www.yageo.com/en/Chart/Download/pdf/CC0402KRX5R6BB224"
			(at 0 0 0)
			(layer "F.Fab")
			(hide yes)
			(effects
				(font
					(size 1.27 1.27)
					(thickness 0.15)
				)
			)
		)
		(property "Author" "Antmicro"
			(at 0 0 0)
			(layer "B.Fab")
			(hide yes)
			(effects
				(font
					(size 1 1)
					(thickness 0.15)
				)
				(justify mirror)
			)
		)
		(property "Dielectric" ""
			(at 0 0 0)
			(layer "B.Fab")
			(hide yes)
			(effects
				(font
					(size 1 1)
					(thickness 0.15)
				)
				(justify mirror)
			)
		)
		(property "License" "Apache-2.0"
			(at 0 0 0)
			(layer "B.Fab")
			(hide yes)
			(effects
				(font
					(size 1 1)
					(thickness 0.15)
				)
				(justify mirror)
			)
		)
		(property "MPN" "CC0402KRX5R6BB224"
			(at 0 0 0)
			(layer "B.Fab")
			(hide yes)
			(effects
				(font
					(size 1 1)
					(thickness 0.15)
				)
				(justify mirror)
			)
		)
		(property "Manufacturer" "YAGEO"
			(at 0 0 0)
			(layer "B.Fab")
			(hide yes)
			(effects
				(font
					(size 1 1)
					(thickness 0.15)
				)
				(justify mirror)
			)
		)
		(property "Val" "220n"
			(at 0 0 0)
			(layer "B.Fab")
			(hide yes)
			(effects
				(font
					(size 1 1)
					(thickness 0.15)
				)
				(justify mirror)
			)
		)
		(property "Voltage" ""
			(at 0 0 0)
			(layer "B.Fab")
			(hide yes)
			(effects
				(font
					(size 1 1)
					(thickness 0.15)
				)
				(justify mirror)
			)
		)
		(sheetname "M.2")
		(sheetfile "m-2.kicad_sch")
		(attr smd)
		(fp_rect
			(start -0.925 0.47)
			(end 0.925 -0.47)
			(stroke
				(width 0.05)
				(type default)
			)
			(fill none)
			(layer "B.CrtYd")
		)
		(fp_line
			(start -0.494 -0.248)
			(end 0.504 -0.248)
			(stroke
				(width 0.15)
				(type solid)
			)
			(layer "B.Fab")
		)
		(fp_line
			(start -0.494 0.25)
			(end -0.494 -0.248)
			(stroke
				(width 0.15)
				(type solid)
			)
			(layer "B.Fab")
		)
		(fp_line
			(start 0.504 -0.248)
			(end 0.504 0.25)
			(stroke
				(width 0.15)
				(type solid)
			)
			(layer "B.Fab")
		)
		(fp_line
			(start 0.504 0.25)
			(end -0.494 0.25)
			(stroke
				(width 0.15)
				(type solid)
			)
			(layer "B.Fab")
		)
		(fp_text user "Author: Antmicro"
			(at -0.932 -4.17 180)
			(layer "B.Fab")
			(hide yes)
			(effects
				(font
					(size 0.7 0.7)
					(thickness 0.15)
				)
				(justify left bottom mirror)
			)
		)
		(fp_text user "License: Apache-2.0"
			(at -0.932 -5.17 180)
			(layer "B.Fab")
			(hide yes)
			(effects
				(font
					(size 0.7 0.7)
					(thickness 0.15)
				)
				(justify left bottom mirror)
			)
		)
		(fp_text user "${REFERENCE}"
			(at -0.932 -3.168 180)
			(layer "B.Fab")
			(hide yes)
			(effects
				(font
					(size 0.7 0.7)
					(thickness 0.15)
				)
				(justify left bottom mirror)
			)
		)
		(pad "1" smd roundrect
			(at -0.48 0)
			(size 0.59 0.64)
			(layers "B.Cu" "B.Paste" "B.Mask")
			(roundrect_rratio 0.25)
			(net 91 "/M.2/C_PCIE0_TX1_N")
			(pintype "passive")
		)
		(pad "2" smd roundrect
			(at 0.48 0)
			(size 0.59 0.64)
			(layers "B.Cu" "B.Paste" "B.Mask")
			(roundrect_rratio 0.25)
			(net 443 "PCIE0_TX1_N")
			(pintype "passive")
		)
	)
	(footprint "antmicro-footprints:R_0402_1005Metric"
		(layer "B.Cu")
		(at 96.2 110.9 -90)
		(descr "Resistor SMD 0402")
		(tags "resistor SMD 0402")
		(property "Reference" "R166"
			(at -1.31 -1.3 90)
			(layer "B.SilkS")
			(effects
				(font
					(size 0.7 0.7)
					(thickness 0.15)
				)
				(justify left bottom mirror)
			)
		)
		(property "Value" "R_0R_0402"
			(at 0 -1.4 90)
			(layer "B.Fab")
			(effects
				(font
					(size 0.7 0.7)
					(thickness 0.15)
				)
				(justify left bottom mirror)
			)
		)
		(property "Footprint" "antmicro-footprints:R_0402_1005Metric"
			(at 0 0 -90)
			(layer "F.Fab")
			(hide yes)
			(effects
				(font
					(size 1.27 1.27)
					(thickness 0.15)
				)
			)
		)
		(property "Datasheet" "https://industrial.panasonic.com/cdbs/www-data/pdf/RDA0000/AOA0000C301.pdf"
			(at 0 0 -90)
			(layer "F.Fab")
			(hide yes)
			(effects
				(font
					(size 1.27 1.27)
					(thickness 0.15)
				)
			)
		)
		(property "Author" "Antmicro"
			(at -14.7 207.1 0)
			(layer "B.Fab")
			(hide yes)
			(effects
				(font
					(size 1 1)
					(thickness 0.15)
				)
				(justify mirror)
			)
		)
		(property "Current" "1A"
			(at -14.7 207.1 0)
			(layer "B.Fab")
			(hide yes)
			(effects
				(font
					(size 1 1)
					(thickness 0.15)
				)
				(justify mirror)
			)
		)
		(property "License" "Apache-2.0"
			(at -14.7 207.1 0)
			(layer "B.Fab")
			(hide yes)
			(effects
				(font
					(size 1 1)
					(thickness 0.15)
				)
				(justify mirror)
			)
		)
		(property "MPN" "ERJ2GE0R00X"
			(at -14.7 207.1 0)
			(layer "B.Fab")
			(hide yes)
			(effects
				(font
					(size 1 1)
					(thickness 0.15)
				)
				(justify mirror)
			)
		)
		(property "Manufacturer" "Panasonic"
			(at -14.7 207.1 0)
			(layer "B.Fab")
			(hide yes)
			(effects
				(font
					(size 1 1)
					(thickness 0.15)
				)
				(justify mirror)
			)
		)
		(property "Tolerance" ""
			(at -14.7 207.1 0)
			(layer "B.Fab")
			(hide yes)
			(effects
				(font
					(size 1 1)
					(thickness 0.15)
				)
				(justify mirror)
			)
		)
		(property "Val" "0R"
			(at -14.7 207.1 0)
			(layer "B.Fab")
			(hide yes)
			(effects
				(font
					(size 1 1)
					(thickness 0.15)
				)
				(justify mirror)
			)
		)
		(sheetname "CSI")
		(sheetfile "csi.kicad_sch")
		(attr smd)
		(fp_rect
			(start -0.925 0.47)
			(end 0.925 -0.47)
			(stroke
				(width 0.05)
				(type default)
			)
			(fill none)
			(layer "B.CrtYd")
		)
		(fp_rect
			(start -0.5 0.25)
			(end 0.5 -0.25)
			(stroke
				(width 0.15)
				(type solid)
			)
			(fill none)
			(layer "B.Fab")
		)
		(fp_text user "Author: Antmicro"
			(at -0.95 -4.169 90)
			(layer "B.Fab")
			(hide yes)
			(effects
				(font
					(size 0.7 0.7)
					(thickness 0.15)
				)
				(justify left bottom mirror)
			)
		)
		(fp_text user "License: Apache-2.0"
			(at -0.95 -5.169 90)
			(layer "B.Fab")
			(hide yes)
			(effects
				(font
					(size 0.7 0.7)
					(thickness 0.15)
				)
				(justify left bottom mirror)
			)
		)
		(fp_text user "${REFERENCE}"
			(at -0.95 -3.168 90)
			(layer "B.Fab")
			(hide yes)
			(effects
				(font
					(size 0.7 0.7)
					(thickness 0.15)
				)
				(justify left bottom mirror)
			)
		)
		(pad "1" smd roundrect
			(at -0.48 0 270)
			(size 0.59 0.64)
			(layers "B.Cu" "B.Paste" "B.Mask")
			(roundrect_rratio 0.25)
			(net 321 "/CSI/CSIA_I2C_VCC")
			(pintype "passive")
		)
		(pad "2" smd roundrect
			(at 0.48 0 270)
			(size 0.59 0.64)
			(layers "B.Cu" "B.Paste" "B.Mask")
			(roundrect_rratio 0.25)
			(net 87 "+3V3")
			(pintype "passive")
		)
	)
	(footprint "antmicro-footprints:R_0402_1005Metric"
		(layer "B.Cu")
		(at 91.3 98.45 90)
		(descr "Resistor SMD 0402")
		(tags "resistor SMD 0402")
		(property "Reference" "R225"
			(at 1.57 -0.45 -90)
			(layer "B.SilkS")
			(effects
				(font
					(size 0.7 0.7)
					(thickness 0.15)
				)
				(justify left bottom mirror)
			)
		)
		(property "Value" "R_0R_0402"
			(at 0 -1.4 -90)
			(layer "B.Fab")
			(effects
				(font
					(size 0.7 0.7)
					(thickness 0.15)
				)
				(justify left bottom mirror)
			)
		)
		(property "Footprint" "antmicro-footprints:R_0402_1005Metric"
			(at 0 0 90)
			(layer "F.Fab")
			(hide yes)
			(effects
				(font
					(size 1.27 1.27)
					(thickness 0.15)
				)
			)
		)
		(property "Datasheet" "https://industrial.panasonic.com/cdbs/www-data/pdf/RDA0000/AOA0000C301.pdf"
			(at 0 0 90)
			(layer "F.Fab")
			(hide yes)
			(effects
				(font
					(size 1.27 1.27)
					(thickness 0.15)
				)
			)
		)
		(property "Author" "Antmicro"
			(at 189.75 7.15 0)
			(layer "B.Fab")
			(hide yes)
			(effects
				(font
					(size 1 1)
					(thickness 0.15)
				)
				(justify mirror)
			)
		)
		(property "Current" "1A"
			(at 189.75 7.15 0)
			(layer "B.Fab")
			(hide yes)
			(effects
				(font
					(size 1 1)
					(thickness 0.15)
				)
				(justify mirror)
			)
		)
		(property "License" "Apache-2.0"
			(at 189.75 7.15 0)
			(layer "B.Fab")
			(hide yes)
			(effects
				(font
					(size 1 1)
					(thickness 0.15)
				)
				(justify mirror)
			)
		)
		(property "MPN" "ERJ2GE0R00X"
			(at 189.75 7.15 0)
			(layer "B.Fab")
			(hide yes)
			(effects
				(font
					(size 1 1)
					(thickness 0.15)
				)
				(justify mirror)
			)
		)
		(property "Manufacturer" "Panasonic"
			(at 189.75 7.15 0)
			(layer "B.Fab")
			(hide yes)
			(effects
				(font
					(size 1 1)
					(thickness 0.15)
				)
				(justify mirror)
			)
		)
		(property "Tolerance" ""
			(at 189.75 7.15 0)
			(layer "B.Fab")
			(hide yes)
			(effects
				(font
					(size 1 1)
					(thickness 0.15)
				)
				(justify mirror)
			)
		)
		(property "Val" "0R"
			(at 189.75 7.15 0)
			(layer "B.Fab")
			(hide yes)
			(effects
				(font
					(size 1 1)
					(thickness 0.15)
				)
				(justify mirror)
			)
		)
		(sheetname "HDMI")
		(sheetfile "hdmi.kicad_sch")
		(attr smd)
		(fp_rect
			(start -0.925 0.47)
			(end 0.925 -0.47)
			(stroke
				(width 0.05)
				(type default)
			)
			(fill none)
			(layer "B.CrtYd")
		)
		(fp_rect
			(start -0.5 0.25)
			(end 0.5 -0.25)
			(stroke
				(width 0.15)
				(type solid)
			)
			(fill none)
			(layer "B.Fab")
		)
		(fp_text user "Author: Antmicro"
			(at -0.95 -4.169 -90)
			(layer "B.Fab")
			(hide yes)
			(effects
				(font
					(size 0.7 0.7)
					(thickness 0.15)
				)
				(justify left bottom mirror)
			)
		)
		(fp_text user "License: Apache-2.0"
			(at -0.95 -5.169 -90)
			(layer "B.Fab")
			(hide yes)
			(effects
				(font
					(size 0.7 0.7)
					(thickness 0.15)
				)
				(justify left bottom mirror)
			)
		)
		(fp_text user "${REFERENCE}"
			(at -0.95 -3.168 -90)
			(layer "B.Fab")
			(hide yes)
			(effects
				(font
					(size 0.7 0.7)
					(thickness 0.15)
				)
				(justify left bottom mirror)
			)
		)
		(pad "1" smd roundrect
			(at -0.48 0 90)
			(size 0.59 0.64)
			(layers "B.Cu" "B.Paste" "B.Mask")
			(roundrect_rratio 0.25)
			(net 703 "/HDMI/HDMI_HPD")
			(pintype "passive")
		)
		(pad "2" smd roundrect
			(at 0.48 0 90)
			(size 0.59 0.64)
			(layers "B.Cu" "B.Paste" "B.Mask")
			(roundrect_rratio 0.25)
			(net 624 "Net-(Q3-D)")
			(pintype "passive")
		)
	)
	(footprint "antmicro-footprints:C_0402_1005Metric"
		(layer "B.Cu")
		(at 126.75 93.75)
		(descr "Capacitor SMD 0402")
		(tags "capacitor SMD 0402")
		(property "Reference" "C20"
			(at -1.15 1.3 0)
			(layer "B.SilkS")
			(effects
				(font
					(size 0.7 0.7)
					(thickness 0.15)
				)
				(justify right bottom mirror)
			)
		)
		(property "Value" "C_220n_0402"
			(at 0 -1.4 0)
			(layer "B.Fab")
			(effects
				(font
					(size 0.7 0.7)
					(thickness 0.15)
				)
				(justify right bottom mirror)
			)
		)
		(property "Footprint" "antmicro-footprints:C_0402_1005Metric"
			(at 0 0 0)
			(layer "F.Fab")
			(hide yes)
			(effects
				(font
					(size 1.27 1.27)
					(thickness 0.15)
				)
			)
		)
		(property "Datasheet" "https://www.yageo.com/en/Chart/Download/pdf/CC0402KRX5R6BB224"
			(at 0 0 0)
			(layer "F.Fab")
			(hide yes)
			(effects
				(font
					(size 1.27 1.27)
					(thickness 0.15)
				)
			)
		)
		(property "Author" "Antmicro"
			(at 0 0 0)
			(layer "B.Fab")
			(hide yes)
			(effects
				(font
					(size 1 1)
					(thickness 0.15)
				)
				(justify mirror)
			)
		)
		(property "Dielectric" ""
			(at 0 0 0)
			(layer "B.Fab")
			(hide yes)
			(effects
				(font
					(size 1 1)
					(thickness 0.15)
				)
				(justify mirror)
			)
		)
		(property "License" "Apache-2.0"
			(at 0 0 0)
			(layer "B.Fab")
			(hide yes)
			(effects
				(font
					(size 1 1)
					(thickness 0.15)
				)
				(justify mirror)
			)
		)
		(property "MPN" "CC0402KRX5R6BB224"
			(at 0 0 0)
			(layer "B.Fab")
			(hide yes)
			(effects
				(font
					(size 1 1)
					(thickness 0.15)
				)
				(justify mirror)
			)
		)
		(property "Manufacturer" "YAGEO"
			(at 0 0 0)
			(layer "B.Fab")
			(hide yes)
			(effects
				(font
					(size 1 1)
					(thickness 0.15)
				)
				(justify mirror)
			)
		)
		(property "Val" "220n"
			(at 0 0 0)
			(layer "B.Fab")
			(hide yes)
			(effects
				(font
					(size 1 1)
					(thickness 0.15)
				)
				(justify mirror)
			)
		)
		(property "Voltage" ""
			(at 0 0 0)
			(layer "B.Fab")
			(hide yes)
			(effects
				(font
					(size 1 1)
					(thickness 0.15)
				)
				(justify mirror)
			)
		)
		(sheetname "M.2")
		(sheetfile "m-2.kicad_sch")
		(attr smd)
		(fp_rect
			(start -0.925 0.47)
			(end 0.925 -0.47)
			(stroke
				(width 0.05)
				(type default)
			)
			(fill none)
			(layer "B.CrtYd")
		)
		(fp_line
			(start -0.494 -0.248)
			(end 0.504 -0.248)
			(stroke
				(width 0.15)
				(type solid)
			)
			(layer "B.Fab")
		)
		(fp_line
			(start -0.494 0.25)
			(end -0.494 -0.248)
			(stroke
				(width 0.15)
				(type solid)
			)
			(layer "B.Fab")
		)
		(fp_line
			(start 0.504 -0.248)
			(end 0.504 0.25)
			(stroke
				(width 0.15)
				(type solid)
			)
			(layer "B.Fab")
		)
		(fp_line
			(start 0.504 0.25)
			(end -0.494 0.25)
			(stroke
				(width 0.15)
				(type solid)
			)
			(layer "B.Fab")
		)
		(fp_text user "${REFERENCE}"
			(at -0.932 -3.168 0)
			(layer "B.Fab")
			(hide yes)
			(effects
				(font
					(size 0.7 0.7)
					(thickness 0.15)
				)
				(justify right bottom mirror)
			)
		)
		(fp_text user "Author: Antmicro"
			(at -0.932 -4.17 0)
			(layer "B.Fab")
			(hide yes)
			(effects
				(font
					(size 0.7 0.7)
					(thickness 0.15)
				)
				(justify right bottom mirror)
			)
		)
		(fp_text user "License: Apache-2.0"
			(at -0.932 -5.17 0)
			(layer "B.Fab")
			(hide yes)
			(effects
				(font
					(size 0.7 0.7)
					(thickness 0.15)
				)
				(justify right bottom mirror)
			)
		)
		(pad "1" smd roundrect
			(at -0.48 0)
			(size 0.59 0.64)
			(layers "B.Cu" "B.Paste" "B.Mask")
			(roundrect_rratio 0.25)
			(net 95 "/M.2/C_PCIE0_TX3_N")
			(pintype "passive")
		)
		(pad "2" smd roundrect
			(at 0.48 0)
			(size 0.59 0.64)
			(layers "B.Cu" "B.Paste" "B.Mask")
			(roundrect_rratio 0.25)
			(net 447 "PCIE0_TX3_N")
			(pintype "passive")
		)
	)
)
